(kicad_pcb
	(version 20260206)
	(generator "pcbnew")
	(generator_version "10.0")
	(general
		(thickness 1.6)
		(legacy_teardrops no)
	)
	(paper "A4")
	(title_block
		(title "01162023_DA0F0TEBIF0_F0T_Expander_BD_F_brd_V02_OCP.brd")
		(comment 1 "Grand Teton / footprints 8632-8640 of 9728")
	)
	(layers
		(0 "F.Cu" signal "TOP")
		(4 "In1.Cu" signal "GND")
		(6 "In2.Cu" signal "VCC")
		(8 "In3.Cu" signal "VCC1")
		(10 "In4.Cu" signal "GND1")
		(12 "In5.Cu" signal "IN1")
		(14 "In6.Cu" signal "GND2")
		(16 "In7.Cu" signal "IN2")
		(18 "In8.Cu" signal "GND3")
		(20 "In9.Cu" signal "IN3")
		(22 "In10.Cu" signal "GND4")
		(24 "In11.Cu" signal "IN4")
		(26 "In12.Cu" signal "GND5")
		(28 "In13.Cu" signal "IN5")
		(30 "In14.Cu" signal "GND6")
		(32 "In15.Cu" signal "IN6")
		(34 "In16.Cu" signal "GND7")
		(2 "B.Cu" signal "BOTTOM")
		(9 "F.Adhes" user "F.Adhesive")
		(11 "B.Adhes" user "B.Adhesive")
		(13 "F.Paste" user "Package Geometry/Pastemask Top")
		(15 "B.Paste" user "Package Geometry/Pastemask Bottom")
		(5 "F.SilkS" user "Ref Des/Silkscreen Top")
		(7 "B.SilkS" user "Ref Des/Silkscreen Bottom")
		(1 "F.Mask" user "Board Geometry/Soldermask Top")
		(3 "B.Mask" user "Board Geometry/Soldermask Bottom")
		(17 "Dwgs.User" user "User.Drawings")
		(19 "Cmts.User" user "User.Comments")
		(21 "Eco1.User" user "User.Eco1")
		(23 "Eco2.User" user "User.Eco2")
		(25 "Edge.Cuts" user "Board Geometry/Outline")
		(27 "Margin" user)
		(31 "F.CrtYd" user "Package Geometry/Place Bound Top")
		(29 "B.CrtYd" user "Package Geometry/Place Bound Bottom")
		(35 "F.Fab" user "Ref Des/Assembly Top")
		(33 "B.Fab" user "Ref Des/Assembly Bottom")
	)
	(footprint ""
		(layer "B.Cu")
		(at 185.250074 -301.124874)
		(property "Reference" "C3168"
			(at 0 0 0)
			(layer "B.SilkS")
			(hide yes)
			(effects
				(font
					(size 1.27 1.27)
				)
				(justify mirror)
			)
		)
		(property "Value" ""
			(at 0 0 0)
			(layer "B.Fab")
			(effects
				(font
					(size 1.27 1.27)
				)
				(justify mirror)
			)
		)
		(duplicate_pad_numbers_are_jumpers no)
		(fp_line
			(start -0.299974 -0.150114)
			(end -0.299974 0.150114)
			(stroke
				(width 0.1)
				(type default)
			)
			(layer "B.Fab")
		)
		(fp_line
			(start -0.299974 0.150114)
			(end 0.299974 0.150114)
			(stroke
				(width 0.1)
				(type default)
			)
			(layer "B.Fab")
		)
		(fp_line
			(start 0.299974 -0.150114)
			(end -0.299974 -0.150114)
			(stroke
				(width 0.1)
				(type default)
			)
			(layer "B.Fab")
		)
		(fp_line
			(start 0.299974 0.150114)
			(end 0.299974 -0.150114)
			(stroke
				(width 0.1)
				(type default)
			)
			(layer "B.Fab")
		)
		(pad "1" smd rect
			(at 0.2667 0 180)
			(size 0.3048 0.381)
			(layers "B.Cu" "B.Mask" "B.Paste")
			(net "P1V8_PEX")
		)
		(pad "2" smd rect
			(at -0.2667 0 180)
			(size 0.3048 0.381)
			(layers "B.Cu" "B.Mask" "B.Paste")
			(net "GND")
		)
	)
	(footprint ""
		(layer "B.Cu")
		(at 71.049896 -294.4749 180)
		(property "Reference" "C2928"
			(at 0 0 0)
			(layer "B.SilkS")
			(hide yes)
			(effects
				(font
					(size 1.27 1.27)
				)
				(justify mirror)
			)
		)
		(property "Value" ""
			(at 0 0 0)
			(layer "B.Fab")
			(effects
				(font
					(size 1.27 1.27)
				)
				(justify mirror)
			)
		)
		(duplicate_pad_numbers_are_jumpers no)
		(fp_line
			(start 0.299974 0.150114)
			(end 0.299974 -0.150114)
			(stroke
				(width 0.1)
				(type default)
			)
			(layer "B.Fab")
		)
		(fp_line
			(start 0.299974 -0.150114)
			(end -0.299974 -0.150114)
			(stroke
				(width 0.1)
				(type default)
			)
			(layer "B.Fab")
		)
		(fp_line
			(start -0.299974 0.150114)
			(end 0.299974 0.150114)
			(stroke
				(width 0.1)
				(type default)
			)
			(layer "B.Fab")
		)
		(fp_line
			(start -0.299974 -0.150114)
			(end -0.299974 0.150114)
			(stroke
				(width 0.1)
				(type default)
			)
			(layer "B.Fab")
		)
		(pad "1" smd rect
			(at 0.2667 0)
			(size 0.3048 0.381)
			(layers "B.Cu" "B.Mask" "B.Paste")
			(net "P1V25_PEX0")
		)
		(pad "2" smd rect
			(at -0.2667 0)
			(size 0.3048 0.381)
			(layers "B.Cu" "B.Mask" "B.Paste")
			(net "GND")
		)
	)
	(footprint ""
		(layer "B.Cu")
		(at 144.841214 -209.841846 -90)
		(property "Reference" "C2590"
			(at 0 0 90)
			(layer "B.SilkS")
			(hide yes)
			(effects
				(font
					(size 1.27 1.27)
				)
				(justify mirror)
			)
		)
		(property "Value" ""
			(at 0 0 90)
			(layer "B.Fab")
			(effects
				(font
					(size 1.27 1.27)
				)
				(justify mirror)
			)
		)
		(duplicate_pad_numbers_are_jumpers no)
		(fp_line
			(start -0.7874 0.4064)
			(end 0.7874 0.4064)
			(stroke
				(width 0.1524)
				(type default)
			)
			(layer "B.SilkS")
		)
		(fp_line
			(start 0.7874 0.4064)
			(end 0.7874 -0.4064)
			(stroke
				(width 0.1524)
				(type default)
			)
			(layer "B.SilkS")
		)
		(fp_line
			(start -0.7874 -0.4064)
			(end -0.7874 0.4064)
			(stroke
				(width 0.1524)
				(type default)
			)
			(layer "B.SilkS")
		)
		(fp_line
			(start 0.7874 -0.4064)
			(end -0.7874 -0.4064)
			(stroke
				(width 0.1524)
				(type default)
			)
			(layer "B.SilkS")
		)
		(fp_line
			(start -0.67945 0.3048)
			(end -0.120396 0.3048)
			(stroke
				(width 0.1)
				(type default)
			)
			(layer "B.Fab")
		)
		(fp_line
			(start -0.120396 0.3048)
			(end -0.120396 0.2794)
			(stroke
				(width 0.1)
				(type default)
			)
			(layer "B.Fab")
		)
		(fp_line
			(start 0.12065 0.3048)
			(end 0.67945 0.3048)
			(stroke
				(width 0.1)
				(type default)
			)
			(layer "B.Fab")
		)
		(fp_line
			(start 0.67945 0.3048)
			(end 0.67945 -0.305054)
			(stroke
				(width 0.1)
				(type default)
			)
			(layer "B.Fab")
		)
		(fp_line
			(start -0.120396 0.2794)
			(end 0.12065 0.2794)
			(stroke
				(width 0.1)
				(type default)
			)
			(layer "B.Fab")
		)
		(fp_line
			(start 0.12065 0.2794)
			(end 0.12065 0.3048)
			(stroke
				(width 0.1)
				(type default)
			)
			(layer "B.Fab")
		)
		(fp_line
			(start -0.12065 -0.2794)
			(end -0.12065 -0.3048)
			(stroke
				(width 0.1)
				(type default)
			)
			(layer "B.Fab")
		)
		(fp_line
			(start 0.12065 -0.2794)
			(end -0.12065 -0.2794)
			(stroke
				(width 0.1)
				(type default)
			)
			(layer "B.Fab")
		)
		(fp_line
			(start -0.67945 -0.3048)
			(end -0.67945 0.3048)
			(stroke
				(width 0.1)
				(type default)
			)
			(layer "B.Fab")
		)
		(fp_line
			(start -0.12065 -0.3048)
			(end -0.67945 -0.3048)
			(stroke
				(width 0.1)
				(type default)
			)
			(layer "B.Fab")
		)
		(fp_line
			(start 0.12065 -0.305054)
			(end 0.12065 -0.2794)
			(stroke
				(width 0.1)
				(type default)
			)
			(layer "B.Fab")
		)
		(fp_line
			(start 0.67945 -0.305054)
			(end 0.12065 -0.305054)
			(stroke
				(width 0.1)
				(type default)
			)
			(layer "B.Fab")
		)
		(pad "1" smd circle
			(at 0.40005 0 90)
			(size 0 0)
			(layers "B.Cu" "B.Mask" "B.Paste")
			(net "P3V3_AUX")
		)
		(pad "2" smd circle
			(at -0.40005 0 90)
			(size 0 0)
			(layers "B.Cu" "B.Mask" "B.Paste")
			(net "GND")
		)
	)
	(footprint ""
		(layer "B.Cu")
		(at 6.93166 -388.602474 180)
		(property "Reference" "C4463"
			(at 0 0 0)
			(layer "B.SilkS")
			(hide yes)
			(effects
				(font
					(size 1.27 1.27)
				)
				(justify mirror)
			)
		)
		(property "Value" ""
			(at 0 0 0)
			(layer "B.Fab")
			(effects
				(font
					(size 1.27 1.27)
				)
				(justify mirror)
			)
		)
		(duplicate_pad_numbers_are_jumpers no)
		(fp_line
			(start 0.7874 0.4064)
			(end 0.7874 -0.4064)
			(stroke
				(width 0.1524)
				(type default)
			)
			(layer "B.SilkS")
		)
		(fp_line
			(start 0.7874 -0.4064)
			(end -0.7874 -0.4064)
			(stroke
				(width 0.1524)
				(type default)
			)
			(layer "B.SilkS")
		)
		(fp_line
			(start -0.7874 0.4064)
			(end 0.7874 0.4064)
			(stroke
				(width 0.1524)
				(type default)
			)
			(layer "B.SilkS")
		)
		(fp_line
			(start -0.7874 -0.4064)
			(end -0.7874 0.4064)
			(stroke
				(width 0.1524)
				(type default)
			)
			(layer "B.SilkS")
		)
		(fp_line
			(start 0.67945 0.3048)
			(end 0.67945 -0.305054)
			(stroke
				(width 0.1)
				(type default)
			)
			(layer "B.Fab")
		)
		(fp_line
			(start 0.67945 -0.305054)
			(end 0.12065 -0.305054)
			(stroke
				(width 0.1)
				(type default)
			)
			(layer "B.Fab")
		)
		(fp_line
			(start 0.12065 0.3048)
			(end 0.67945 0.3048)
			(stroke
				(width 0.1)
				(type default)
			)
			(layer "B.Fab")
		)
		(fp_line
			(start 0.12065 0.2794)
			(end 0.12065 0.3048)
			(stroke
				(width 0.1)
				(type default)
			)
			(layer "B.Fab")
		)
		(fp_line
			(start 0.12065 -0.2794)
			(end -0.12065 -0.2794)
			(stroke
				(width 0.1)
				(type default)
			)
			(layer "B.Fab")
		)
		(fp_line
			(start 0.12065 -0.305054)
			(end 0.12065 -0.2794)
			(stroke
				(width 0.1)
				(type default)
			)
			(layer "B.Fab")
		)
		(fp_line
			(start -0.120396 0.3048)
			(end -0.120396 0.2794)
			(stroke
				(width 0.1)
				(type default)
			)
			(layer "B.Fab")
		)
		(fp_line
			(start -0.120396 0.2794)
			(end 0.12065 0.2794)
			(stroke
				(width 0.1)
				(type default)
			)
			(layer "B.Fab")
		)
		(fp_line
			(start -0.12065 -0.2794)
			(end -0.12065 -0.3048)
			(stroke
				(width 0.1)
				(type default)
			)
			(layer "B.Fab")
		)
		(fp_line
			(start -0.12065 -0.3048)
			(end -0.67945 -0.3048)
			(stroke
				(width 0.1)
				(type default)
			)
			(layer "B.Fab")
		)
		(fp_line
			(start -0.67945 0.3048)
			(end -0.120396 0.3048)
			(stroke
				(width 0.1)
				(type default)
			)
			(layer "B.Fab")
		)
		(fp_line
			(start -0.67945 -0.3048)
			(end -0.67945 0.3048)
			(stroke
				(width 0.1)
				(type default)
			)
			(layer "B.Fab")
		)
		(pad "1" smd circle
			(at 0.40005 0)
			(size 0 0)
			(layers "B.Cu" "B.Mask" "B.Paste")
			(net "P3V3_USB_8042")
		)
		(pad "2" smd circle
			(at -0.40005 0)
			(size 0 0)
			(layers "B.Cu" "B.Mask" "B.Paste")
			(net "GND")
		)
	)
	(footprint ""
		(layer "B.Cu")
		(at 242.051078 -234.056428 -90)
		(property "Reference" "C4489"
			(at 0 0 90)
			(layer "B.SilkS")
			(hide yes)
			(effects
				(font
					(size 1.27 1.27)
				)
				(justify mirror)
			)
		)
		(property "Value" ""
			(at 0 0 90)
			(layer "B.Fab")
			(effects
				(font
					(size 1.27 1.27)
				)
				(justify mirror)
			)
		)
		(duplicate_pad_numbers_are_jumpers no)
		(fp_line
			(start -0.7874 0.4064)
			(end 0.7874 0.4064)
			(stroke
				(width 0.1524)
				(type default)
			)
			(layer "B.SilkS")
		)
		(fp_line
			(start 0.7874 0.4064)
			(end 0.7874 -0.4064)
			(stroke
				(width 0.1524)
				(type default)
			)
			(layer "B.SilkS")
		)
		(fp_line
			(start -0.7874 -0.4064)
			(end -0.7874 0.4064)
			(stroke
				(width 0.1524)
				(type default)
			)
			(layer "B.SilkS")
		)
		(fp_line
			(start 0.7874 -0.4064)
			(end -0.7874 -0.4064)
			(stroke
				(width 0.1524)
				(type default)
			)
			(layer "B.SilkS")
		)
		(fp_line
			(start -0.67945 0.3048)
			(end -0.120396 0.3048)
			(stroke
				(width 0.1)
				(type default)
			)
			(layer "B.Fab")
		)
		(fp_line
			(start -0.120396 0.3048)
			(end -0.120396 0.2794)
			(stroke
				(width 0.1)
				(type default)
			)
			(layer "B.Fab")
		)
		(fp_line
			(start 0.12065 0.3048)
			(end 0.67945 0.3048)
			(stroke
				(width 0.1)
				(type default)
			)
			(layer "B.Fab")
		)
		(fp_line
			(start 0.67945 0.3048)
			(end 0.67945 -0.305054)
			(stroke
				(width 0.1)
				(type default)
			)
			(layer "B.Fab")
		)
		(fp_line
			(start -0.120396 0.2794)
			(end 0.12065 0.2794)
			(stroke
				(width 0.1)
				(type default)
			)
			(layer "B.Fab")
		)
		(fp_line
			(start 0.12065 0.2794)
			(end 0.12065 0.3048)
			(stroke
				(width 0.1)
				(type default)
			)
			(layer "B.Fab")
		)
		(fp_line
			(start -0.12065 -0.2794)
			(end -0.12065 -0.3048)
			(stroke
				(width 0.1)
				(type default)
			)
			(layer "B.Fab")
		)
		(fp_line
			(start 0.12065 -0.2794)
			(end -0.12065 -0.2794)
			(stroke
				(width 0.1)
				(type default)
			)
			(layer "B.Fab")
		)
		(fp_line
			(start -0.67945 -0.3048)
			(end -0.67945 0.3048)
			(stroke
				(width 0.1)
				(type default)
			)
			(layer "B.Fab")
		)
		(fp_line
			(start -0.12065 -0.3048)
			(end -0.67945 -0.3048)
			(stroke
				(width 0.1)
				(type default)
			)
			(layer "B.Fab")
		)
		(fp_line
			(start 0.12065 -0.305054)
			(end 0.12065 -0.2794)
			(stroke
				(width 0.1)
				(type default)
			)
			(layer "B.Fab")
		)
		(fp_line
			(start 0.67945 -0.305054)
			(end 0.12065 -0.305054)
			(stroke
				(width 0.1)
				(type default)
			)
			(layer "B.Fab")
		)
		(pad "1" smd circle
			(at 0.40005 0 90)
			(size 0 0)
			(layers "B.Cu" "B.Mask" "B.Paste")
			(net "BOARD_TYPE_2_ADC_R")
		)
		(pad "2" smd circle
			(at -0.40005 0 90)
			(size 0 0)
			(layers "B.Cu" "B.Mask" "B.Paste")
			(net "GND")
		)
	)
	(footprint ""
		(layer "B.Cu")
		(at 169.574972 -286.399732 90)
		(property "Reference" "C3150"
			(at 0 0 90)
			(layer "B.SilkS")
			(hide yes)
			(effects
				(font
					(size 1.27 1.27)
				)
				(justify mirror)
			)
		)
		(property "Value" ""
			(at 0 0 90)
			(layer "B.Fab")
			(effects
				(font
					(size 1.27 1.27)
				)
				(justify mirror)
			)
		)
		(duplicate_pad_numbers_are_jumpers no)
		(fp_line
			(start 0.299974 -0.150114)
			(end -0.299974 -0.150114)
			(stroke
				(width 0.1)
				(type default)
			)
			(layer "B.Fab")
		)
		(fp_line
			(start -0.299974 -0.150114)
			(end -0.299974 0.150114)
			(stroke
				(width 0.1)
				(type default)
			)
			(layer "B.Fab")
		)
		(fp_line
			(start 0.299974 0.150114)
			(end 0.299974 -0.150114)
			(stroke
				(width 0.1)
				(type default)
			)
			(layer "B.Fab")
		)
		(fp_line
			(start -0.299974 0.150114)
			(end 0.299974 0.150114)
			(stroke
				(width 0.1)
				(type default)
			)
			(layer "B.Fab")
		)
		(pad "1" smd rect
			(at 0.2667 0 270)
			(size 0.3048 0.381)
			(layers "B.Cu" "B.Mask" "B.Paste")
			(net "P1V25_SERDES_VDDPLL_PEX1")
		)
		(pad "2" smd rect
			(at -0.2667 0 270)
			(size 0.3048 0.381)
			(layers "B.Cu" "B.Mask" "B.Paste")
			(net "GND")
		)
	)
	(footprint ""
		(layer "B.Cu")
		(at 288.469832 -305.399948 -90)
		(property "Reference" "C3311"
			(at 0 0 90)
			(layer "B.SilkS")
			(hide yes)
			(effects
				(font
					(size 1.27 1.27)
				)
				(justify mirror)
			)
		)
		(property "Value" ""
			(at 0 0 90)
			(layer "B.Fab")
			(effects
				(font
					(size 1.27 1.27)
				)
				(justify mirror)
			)
		)
		(duplicate_pad_numbers_are_jumpers no)
		(fp_line
			(start -0.299974 0.150114)
			(end 0.299974 0.150114)
			(stroke
				(width 0.1)
				(type default)
			)
			(layer "B.Fab")
		)
		(fp_line
			(start 0.299974 0.150114)
			(end 0.299974 -0.150114)
			(stroke
				(width 0.1)
				(type default)
			)
			(layer "B.Fab")
		)
		(fp_line
			(start -0.299974 -0.150114)
			(end -0.299974 0.150114)
			(stroke
				(width 0.1)
				(type default)
			)
			(layer "B.Fab")
		)
		(fp_line
			(start 0.299974 -0.150114)
			(end -0.299974 -0.150114)
			(stroke
				(width 0.1)
				(type default)
			)
			(layer "B.Fab")
		)
		(pad "1" smd rect
			(at 0.2667 0 90)
			(size 0.3048 0.381)
			(layers "B.Cu" "B.Mask" "B.Paste")
			(net "P1V25_SERDES_VDDPLL_PEX2")
		)
		(pad "2" smd rect
			(at -0.2667 0 90)
			(size 0.3048 0.381)
			(layers "B.Cu" "B.Mask" "B.Paste")
			(net "GND")
		)
	)
	(footprint ""
		(layer "B.Cu")
		(at 394.164312 -146.148552 180)
		(property "Reference" "C939"
			(at 0 0 0)
			(layer "B.SilkS")
			(hide yes)
			(effects
				(font
					(size 1.27 1.27)
				)
				(justify mirror)
			)
		)
		(property "Value" ""
			(at 0 0 0)
			(layer "B.Fab")
			(effects
				(font
					(size 1.27 1.27)
				)
				(justify mirror)
			)
		)
		(duplicate_pad_numbers_are_jumpers no)
		(fp_line
			(start 0.299974 0.150114)
			(end 0.299974 -0.150114)
			(stroke
				(width 0.1)
				(type default)
			)
			(layer "B.Fab")
		)
		(fp_line
			(start 0.299974 -0.150114)
			(end -0.299974 -0.150114)
			(stroke
				(width 0.1)
				(type default)
			)
			(layer "B.Fab")
		)
		(fp_line
			(start -0.299974 0.150114)
			(end 0.299974 0.150114)
			(stroke
				(width 0.1)
				(type default)
			)
			(layer "B.Fab")
		)
		(fp_line
			(start -0.299974 -0.150114)
			(end -0.299974 0.150114)
			(stroke
				(width 0.1)
				(type default)
			)
			(layer "B.Fab")
		)
		(pad "1" smd rect
			(at 0.2667 0)
			(size 0.3048 0.381)
			(layers "B.Cu" "B.Mask" "B.Paste")
			(net "P12V_NIC6")
		)
		(pad "2" smd rect
			(at -0.2667 0)
			(size 0.3048 0.381)
			(layers "B.Cu" "B.Mask" "B.Paste")
			(net "GND")
		)
	)
	(footprint ""
		(layer "B.Cu")
		(at 128.470914 -182.604664 -90)
		(property "Reference" "R1120"
			(at 0 0 90)
			(layer "B.SilkS")
			(hide yes)
			(effects
				(font
					(size 1.27 1.27)
				)
				(justify mirror)
			)
		)
		(property "Value" ""
			(at 0 0 90)
			(layer "B.Fab")
			(effects
				(font
					(size 1.27 1.27)
				)
				(justify mirror)
			)
		)
		(duplicate_pad_numbers_are_jumpers no)
		(fp_line
			(start -0.7874 0.4064)
			(end 0.7874 0.4064)
			(stroke
				(width 0.1524)
				(type default)
			)
			(layer "B.SilkS")
		)
		(fp_line
			(start 0.7874 0.4064)
			(end 0.7874 -0.4064)
			(stroke
				(width 0.1524)
				(type default)
			)
			(layer "B.SilkS")
		)
		(fp_line
			(start -0.7874 -0.4064)
			(end -0.7874 0.4064)
			(stroke
				(width 0.1524)
				(type default)
			)
			(layer "B.SilkS")
		)
		(fp_line
			(start 0.7874 -0.4064)
			(end -0.7874 -0.4064)
			(stroke
				(width 0.1524)
				(type default)
			)
			(layer "B.SilkS")
		)
		(fp_line
			(start -0.67945 0.3048)
			(end -0.120396 0.3048)
			(stroke
				(width 0.1)
				(type default)
			)
			(layer "B.Fab")
		)
		(fp_line
			(start -0.120396 0.3048)
			(end -0.120396 0.2794)
			(stroke
				(width 0.1)
				(type default)
			)
			(layer "B.Fab")
		)
		(fp_line
			(start 0.12065 0.3048)
			(end 0.67945 0.3048)
			(stroke
				(width 0.1)
				(type default)
			)
			(layer "B.Fab")
		)
		(fp_line
			(start 0.67945 0.3048)
			(end 0.67945 -0.305054)
			(stroke
				(width 0.1)
				(type default)
			)
			(layer "B.Fab")
		)
		(fp_line
			(start -0.120396 0.2794)
			(end 0.12065 0.2794)
			(stroke
				(width 0.1)
				(type default)
			)
			(layer "B.Fab")
		)
		(fp_line
			(start 0.12065 0.2794)
			(end 0.12065 0.3048)
			(stroke
				(width 0.1)
				(type default)
			)
			(layer "B.Fab")
		)
		(fp_line
			(start -0.12065 -0.2794)
			(end -0.12065 -0.3048)
			(stroke
				(width 0.1)
				(type default)
			)
			(layer "B.Fab")
		)
		(fp_line
			(start 0.12065 -0.2794)
			(end -0.12065 -0.2794)
			(stroke
				(width 0.1)
				(type default)
			)
			(layer "B.Fab")
		)
		(fp_line
			(start -0.67945 -0.3048)
			(end -0.67945 0.3048)
			(stroke
				(width 0.1)
				(type default)
			)
			(layer "B.Fab")
		)
		(fp_line
			(start -0.12065 -0.3048)
			(end -0.67945 -0.3048)
			(stroke
				(width 0.1)
				(type default)
			)
			(layer "B.Fab")
		)
		(fp_line
			(start 0.12065 -0.305054)
			(end 0.12065 -0.2794)
			(stroke
				(width 0.1)
				(type default)
			)
			(layer "B.Fab")
		)
		(fp_line
			(start 0.67945 -0.305054)
			(end 0.12065 -0.305054)
			(stroke
				(width 0.1)
				(type default)
			)
			(layer "B.Fab")
		)
		(pad "1" smd circle
			(at 0.40005 0 90)
			(size 0 0)
			(layers "B.Cu" "B.Mask" "B.Paste")
			(net "FM_DB2000QL_SMB_SA0")
		)
		(pad "2" smd circle
			(at -0.40005 0 90)
			(size 0 0)
			(layers "B.Cu" "B.Mask" "B.Paste")
			(net "P3V3")
		)
	)
)
